# BASEBOARD_FAB2 (Tioga Pass) — schematic netlist excerpt (pin names and nets, part order shuffled) for the footprints in the layout excerpt that follows; sources: Cadence DE-HDL packaged netlist, KiCad conversion of Wiwynn_Tioga_Pass_MB.brd

R4T5  RES  240 1.0% CHIP  pkg 0402  page 99 : A = PVCCIO_CPU0 ; B = SMB_DDR_ABC_SCL_G

U25W7  U74AHCT1G125G-AL5-R-GP-U  pkg TTL-G4  page 252
  \oe#\  = GND
  A  = BMC_VGA_HSYNC
  GND  = GND
  Y  = VGA_REAR_HSYNC_S
  VCC  = P5V_VGA_D

(kicad_pcb
	(version 20260206)
	(generator "pcbnew")
	(generator_version "10.0")
	(general
		(thickness 1.6)
		(legacy_teardrops no)
	)
	(paper "A4")
	(title_block
		(title "Wiwynn_Tioga_Pass_MB.brd")
		(comment 1 "Tioga Pass / footprints 3611-3612 of 4770")
	)
	(layers
		(0 "F.Cu" signal "TOP")
		(4 "In1.Cu" signal "L2GND")
		(6 "In2.Cu" signal "L3")
		(8 "In3.Cu" signal "L4GND")
		(10 "In4.Cu" signal "L5")
		(12 "In5.Cu" signal "L6GND")
		(14 "In6.Cu" signal "L7VCC")
		(16 "In7.Cu" signal "L8VCC")
		(18 "In8.Cu" signal "L9GND")
		(20 "In9.Cu" signal "L10")
		(22 "In10.Cu" signal "L11GND")
		(24 "In11.Cu" signal "L12")
		(26 "In12.Cu" signal "L13GND")
		(2 "B.Cu" signal "BOTTOM")
		(9 "F.Adhes" user "F.Adhesive")
		(11 "B.Adhes" user "B.Adhesive")
		(13 "F.Paste" user "Package Geometry/Pastemask Top")
		(15 "B.Paste" user "Package Geometry/Pastemask Bottom")
		(5 "F.SilkS" user "Ref Des/Silkscreen Top")
		(7 "B.SilkS" user "Ref Des/Silkscreen Bottom")
		(1 "F.Mask" user "Board Geometry/Soldermask Top")
		(3 "B.Mask" user "Board Geometry/Soldermask Bottom")
		(17 "Dwgs.User" user "User.Drawings")
		(19 "Cmts.User" user "User.Comments")
		(21 "Eco1.User" user "User.Eco1")
		(23 "Eco2.User" user "User.Eco2")
		(25 "Edge.Cuts" user "Board Geometry/Outline")
		(27 "Margin" user)
		(31 "F.CrtYd" user "Package Geometry/Place Bound Top")
		(29 "B.CrtYd" user "Package Geometry/Place Bound Bottom")
		(35 "F.Fab" user "Ref Des/Assembly Top")
		(33 "B.Fab" user "Ref Des/Assembly Bottom")
	)
	(footprint ""
		(layer "B.Cu")
		(at 495.676174 -40.573706)
		(property "Reference" "U25W7"
			(at 0 0 0)
			(layer "B.SilkS")
			(hide yes)
			(effects
				(font
					(size 1.27 1.27)
				)
				(justify mirror)
			)
		)
		(property "Value" "*"
			(at 0 -10.7315 0)
			(unlocked yes)
			(layer "B.Fab")
			(hide yes)
			(effects
				(font
					(size 1.27 1.016)
					(thickness 0.1524)
				)
				(justify mirror)
			)
		)
		(property "Device Type" "U74AHCT1G125G-AL5-R-GP-U_TTL-GA"
			(at 0 -12.2555 0)
			(unlocked yes)
			(layer "B.Fab")
			(hide yes)
			(effects
				(font
					(size 1.27 1.016)
					(thickness 0.1524)
				)
				(justify mirror)
			)
		)
		(duplicate_pad_numbers_are_jumpers no)
		(fp_line
			(start -1.24714 -1.79832)
			(end -1.24714 1.82372)
			(stroke
				(width 0.1524)
				(type default)
			)
			(layer "B.SilkS")
		)
		(fp_line
			(start -1.2446 1.81102)
			(end -1.25476 1.82118)
			(stroke
				(width 0.1524)
				(type default)
			)
			(layer "B.SilkS")
		)
		(fp_line
			(start -1.08712 -1.80848)
			(end 1.23952 -1.80848)
			(stroke
				(width 0.1524)
				(type default)
			)
			(layer "B.SilkS")
		)
		(fp_line
			(start -1.08204 -1.80848)
			(end -1.26492 -1.80848)
			(stroke
				(width 0.1524)
				(type default)
			)
			(layer "B.SilkS")
		)
		(fp_line
			(start -1.08204 1.81102)
			(end 1.4859 1.81102)
			(stroke
				(width 0.1524)
				(type default)
			)
			(layer "B.SilkS")
		)
		(fp_line
			(start -1.06934 1.81102)
			(end -1.2446 1.81102)
			(stroke
				(width 0.1524)
				(type default)
			)
			(layer "B.SilkS")
		)
		(fp_line
			(start 1.2446 1.8034)
			(end 1.2446 -1.8161)
			(stroke
				(width 0.1524)
				(type default)
			)
			(layer "B.SilkS")
		)
		(fp_line
			(start 1.3081 0.49022)
			(end 1.3081 1.7907)
			(stroke
				(width 0.508)
				(type default)
			)
			(layer "B.SilkS")
		)
		(fp_poly
			(pts
				(xy 0.82804 0.10922) (xy -0.82804 0.10922) (xy -0.82804 -0.10795) (xy 0.82804 -0.10795)
			)
			(stroke
				(width 0)
				(type default)
			)
			(fill yes)
			(layer "B.SilkS")
		)
		(fp_poly
			(pts
				(xy 1.5621 2.0447) (xy -1.5621 2.0447) (xy -1.5621 -2.0447) (xy 1.5621 -2.0447)
			)
			(stroke
				(width 0)
				(type default)
			)
			(fill no)
			(layer "B.CrtYd")
		)
		(fp_poly
			(pts
				(xy 1.5621 -2.0447) (xy -1.5621 -2.0447) (xy -1.5621 2.0447) (xy 1.5621 2.0447)
			)
			(stroke
				(width 0)
				(type default)
			)
			(fill no)
			(layer "B.Fab")
		)
		(pad "1" smd rect
			(at 0.65024 0.92202 180)
			(size 0.3556 1.2192)
			(layers "B.Cu" "B.Mask" "B.Paste")
			(net "GND")
		)
		(pad "2" smd rect
			(at 0 0.92202 180)
			(size 0.3556 1.2192)
			(layers "B.Cu" "B.Mask" "B.Paste")
			(net "BMC_VGA_HSYNC")
		)
		(pad "3" smd rect
			(at -0.65024 0.92202 180)
			(size 0.3556 1.2192)
			(layers "B.Cu" "B.Mask" "B.Paste")
			(net "GND")
		)
		(pad "4" smd rect
			(at -0.65024 -0.92075 180)
			(size 0.3556 1.2192)
			(layers "B.Cu" "B.Mask" "B.Paste")
			(net "VGA_REAR_HSYNC_S")
		)
		(pad "5" smd rect
			(at 0.65024 -0.92075 180)
			(size 0.3556 1.2192)
			(layers "B.Cu" "B.Mask" "B.Paste")
			(net "P5V_VGA_D")
		)
	)
	(footprint ""
		(layer "B.Cu")
		(at 323.8627 -31.967678 -90)
		(property "Reference" "R4T5"
			(at 0 0 90)
			(layer "B.SilkS")
			(hide yes)
			(effects
				(font
					(size 1.27 1.27)
				)
				(justify mirror)
			)
		)
		(property "Value" ""
			(at 0 0 90)
			(layer "B.Fab")
			(effects
				(font
					(size 1.27 1.27)
				)
				(justify mirror)
			)
		)
		(duplicate_pad_numbers_are_jumpers no)
		(fp_poly
			(pts
				(xy 0.2794 -0.1016) (xy -0.2794 -0.1016) (xy -0.2794 0.9906) (xy 0.2794 0.9906)
			)
			(stroke
				(width 0)
				(type default)
			)
			(fill no)
			(layer "B.CrtYd")
		)
		(fp_line
			(start -0.2794 0.9906)
			(end -0.2794 -0.1016)
			(stroke
				(width 0.1)
				(type default)
			)
			(layer "B.Fab")
		)
		(fp_line
			(start 0.2794 0.9906)
			(end -0.2794 0.9906)
			(stroke
				(width 0.1)
				(type default)
			)
			(layer "B.Fab")
		)
		(fp_line
			(start -0.2794 -0.1016)
			(end 0.2794 -0.1016)
			(stroke
				(width 0.1)
				(type default)
			)
			(layer "B.Fab")
		)
		(fp_line
			(start 0.2794 -0.1016)
			(end 0.2794 0.9906)
			(stroke
				(width 0.1)
				(type default)
			)
			(layer "B.Fab")
		)
		(pad "1" smd rect
			(at 0 0 90)
			(size 0.508 0.508)
			(layers "B.Cu" "B.Mask" "B.Paste")
			(net "PVCCIO_CPU0")
		)
		(pad "2" smd rect
			(at 0 0.889 90)
			(size 0.508 0.508)
			(layers "B.Cu" "B.Mask" "B.Paste")
			(net "SMB_DDR_ABC_SCL_G")
		)
		(zone
			(layer "B.Cu")
			(hatch none 0.5)
			(connect_pads
				(clearance 0)
			)
			(min_thickness 0.25)
			(keepout
				(tracks not_allowed)
				(vias allowed)
				(pads allowed)
				(copperpour not_allowed)
				(footprints allowed)
			)
			(placement
				(enabled no)
				(sheetname "")
			)
			(fill
				(thermal_gap 0.5)
				(thermal_bridge_width 0.5)
				(island_removal_mode 0)
			)
			(polygon
				(pts
					(xy 323.2277 -31.713678) (xy 323.2277 -32.221678) (xy 323.6087 -32.221678) (xy 323.6087 -31.713678)
				)
			)
		)
		(zone
			(layer "B.Cu")
			(hatch none 0.5)
			(connect_pads
				(clearance 0)
			)
			(min_thickness 0.25)
			(keepout
				(tracks allowed)
				(vias not_allowed)
				(pads allowed)
				(copperpour not_allowed)
				(footprints allowed)
			)
			(placement
				(enabled no)
				(sheetname "")
			)
			(fill
				(thermal_gap 0.5)
				(thermal_bridge_width 0.5)
				(island_removal_mode 0)
			)
			(polygon
				(pts
					(xy 323.6087 -31.713678) (xy 323.6087 -32.221678) (xy 323.2277 -32.221678) (xy 323.2277 -31.713678)
				)
			)
		)
	)
)
